# T6G (Grand Teton) — schematic netlist excerpt (pin names and nets, part order shuffled) for the footprints in the layout excerpt that follows; sources: Cadence DE-HDL packaged netlist, KiCad conversion of 04192023_DAF0TMB3IC0_F0TG_MB_C_brd_V02_OCP.brd

R355  Q_RES  10.5K 1% CHIP  pkg 0402LF  page 267 : A = P3V3_AUX ; B = P12V_HSC_TEMP_ALERT_R_N
C811  Q_CAP_DIFFBUS  DIFF BUS_0.22UF 6.3V 20% X6S  pkg C0201  page 65 : \1\ = P5E_CPU1_P0_TX_C_DP<13> ; \2\ = P5E_CPU1_P0_TX_DP<13>

(kicad_pcb
	(version 20260206)
	(generator "pcbnew")
	(generator_version "10.0")
	(general
		(thickness 1.6)
		(legacy_teardrops no)
	)
	(paper "A4")
	(title_block
		(title "04192023_DAF0TMB3IC0_F0TG_MB_C_brd_V02_OCP.brd")
		(comment 1 "Grand Teton / footprints 2032-2033 of 8354")
	)
	(layers
		(0 "F.Cu" signal "TOP")
		(4 "In1.Cu" signal "GND")
		(6 "In2.Cu" signal "IN1")
		(8 "In3.Cu" signal "GND1")
		(10 "In4.Cu" signal "IN2")
		(12 "In5.Cu" signal "GND2")
		(14 "In6.Cu" signal "IN3")
		(16 "In7.Cu" signal "GND3")
		(18 "In8.Cu" signal "VCC")
		(20 "In9.Cu" signal "VCC1")
		(22 "In10.Cu" signal "GND4")
		(24 "In11.Cu" signal "IN4")
		(26 "In12.Cu" signal "GND5")
		(28 "In13.Cu" signal "IN5")
		(30 "In14.Cu" signal "GND6")
		(32 "In15.Cu" signal "IN6")
		(34 "In16.Cu" signal "GND7")
		(2 "B.Cu" signal "BOTTOM")
		(9 "F.Adhes" user "F.Adhesive")
		(11 "B.Adhes" user "B.Adhesive")
		(13 "F.Paste" user "Package Geometry/Pastemask Top")
		(15 "B.Paste" user "Package Geometry/Pastemask Bottom")
		(5 "F.SilkS" user "Ref Des/Silkscreen Top")
		(7 "B.SilkS" user "Ref Des/Silkscreen Bottom")
		(1 "F.Mask" user "Board Geometry/Soldermask Top")
		(3 "B.Mask" user "Board Geometry/Soldermask Bottom")
		(17 "Dwgs.User" user "User.Drawings")
		(19 "Cmts.User" user "User.Comments")
		(21 "Eco1.User" user "User.Eco1")
		(23 "Eco2.User" user "User.Eco2")
		(25 "Edge.Cuts" user "Board Geometry/Outline")
		(27 "Margin" user)
		(31 "F.CrtYd" user "Package Geometry/Place Bound Top")
		(29 "B.CrtYd" user "Package Geometry/Place Bound Bottom")
		(35 "F.Fab" user "Ref Des/Assembly Top")
		(33 "B.Fab" user "Ref Des/Assembly Bottom")
	)
	(footprint ""
		(layer "F.Cu")
		(at 281.827732 -392.705844 90)
		(property "Reference" "R355"
			(at 0 0 90)
			(layer "F.SilkS")
			(hide yes)
			(effects
				(font
					(size 1.27 1.27)
				)
			)
		)
		(property "Value" ""
			(at 0 0 90)
			(layer "F.Fab")
			(effects
				(font
					(size 1.27 1.27)
				)
			)
		)
		(duplicate_pad_numbers_are_jumpers no)
		(fp_line
			(start 0.7874 -0.4064)
			(end 0.7874 0.4064)
			(stroke
				(width 0.1524)
				(type default)
			)
			(layer "F.SilkS")
		)
		(fp_line
			(start -0.7874 -0.4064)
			(end 0.7874 -0.4064)
			(stroke
				(width 0.1524)
				(type default)
			)
			(layer "F.SilkS")
		)
		(fp_line
			(start 0.7874 0.4064)
			(end -0.7874 0.4064)
			(stroke
				(width 0.1524)
				(type default)
			)
			(layer "F.SilkS")
		)
		(fp_line
			(start -0.7874 0.4064)
			(end -0.7874 -0.4064)
			(stroke
				(width 0.1524)
				(type default)
			)
			(layer "F.SilkS")
		)
		(fp_line
			(start -0.12065 -0.305054)
			(end -0.12065 -0.2794)
			(stroke
				(width 0.1)
				(type default)
			)
			(layer "F.Fab")
		)
		(fp_line
			(start -0.67945 -0.305054)
			(end -0.12065 -0.305054)
			(stroke
				(width 0.1)
				(type default)
			)
			(layer "F.Fab")
		)
		(fp_line
			(start 0.67945 -0.3048)
			(end 0.67945 0.3048)
			(stroke
				(width 0.1)
				(type default)
			)
			(layer "F.Fab")
		)
		(fp_line
			(start 0.12065 -0.3048)
			(end 0.67945 -0.3048)
			(stroke
				(width 0.1)
				(type default)
			)
			(layer "F.Fab")
		)
		(fp_line
			(start 0.12065 -0.2794)
			(end 0.12065 -0.3048)
			(stroke
				(width 0.1)
				(type default)
			)
			(layer "F.Fab")
		)
		(fp_line
			(start -0.12065 -0.2794)
			(end 0.12065 -0.2794)
			(stroke
				(width 0.1)
				(type default)
			)
			(layer "F.Fab")
		)
		(fp_line
			(start 0.120396 0.2794)
			(end -0.12065 0.2794)
			(stroke
				(width 0.1)
				(type default)
			)
			(layer "F.Fab")
		)
		(fp_line
			(start -0.12065 0.2794)
			(end -0.12065 0.3048)
			(stroke
				(width 0.1)
				(type default)
			)
			(layer "F.Fab")
		)
		(fp_line
			(start 0.67945 0.3048)
			(end 0.120396 0.3048)
			(stroke
				(width 0.1)
				(type default)
			)
			(layer "F.Fab")
		)
		(fp_line
			(start 0.120396 0.3048)
			(end 0.120396 0.2794)
			(stroke
				(width 0.1)
				(type default)
			)
			(layer "F.Fab")
		)
		(fp_line
			(start -0.12065 0.3048)
			(end -0.67945 0.3048)
			(stroke
				(width 0.1)
				(type default)
			)
			(layer "F.Fab")
		)
		(fp_line
			(start -0.67945 0.3048)
			(end -0.67945 -0.305054)
			(stroke
				(width 0.1)
				(type default)
			)
			(layer "F.Fab")
		)
		(pad "1" smd circle
			(at -0.40005 0 90)
			(size 0 0)
			(layers "F.Cu" "F.Mask" "F.Paste")
			(net "P3V3_AUX")
		)
		(pad "2" smd circle
			(at 0.40005 0 90)
			(size 0 0)
			(layers "F.Cu" "F.Mask" "F.Paste")
			(net "P12V_HSC_TEMP_ALERT_R_N")
		)
	)
	(footprint ""
		(layer "F.Cu")
		(at 69.431154 -370.57203 -90)
		(property "Reference" "C811"
			(at 0 0 270)
			(layer "F.SilkS")
			(hide yes)
			(effects
				(font
					(size 1.27 1.27)
				)
			)
		)
		(property "Value" ""
			(at 0 0 270)
			(layer "F.Fab")
			(effects
				(font
					(size 1.27 1.27)
				)
			)
		)
		(duplicate_pad_numbers_are_jumpers no)
		(fp_line
			(start -0.299974 0.150114)
			(end -0.299974 -0.150114)
			(stroke
				(width 0.1)
				(type default)
			)
			(layer "F.Fab")
		)
		(fp_line
			(start 0.299974 0.150114)
			(end -0.299974 0.150114)
			(stroke
				(width 0.1)
				(type default)
			)
			(layer "F.Fab")
		)
		(fp_line
			(start -0.299974 -0.150114)
			(end 0.299974 -0.150114)
			(stroke
				(width 0.1)
				(type default)
			)
			(layer "F.Fab")
		)
		(fp_line
			(start 0.299974 -0.150114)
			(end 0.299974 0.150114)
			(stroke
				(width 0.1)
				(type default)
			)
			(layer "F.Fab")
		)
		(pad "1" smd rect
			(at -0.2667 0 270)
			(size 0.3048 0.381)
			(layers "F.Cu" "F.Mask" "F.Paste")
			(net "P5E_CPU1_P0_TX_C_DP<13>")
		)
		(pad "2" smd rect
			(at 0.2667 0 270)
			(size 0.3048 0.381)
			(layers "F.Cu" "F.Mask" "F.Paste")
			(net "P5E_CPU1_P0_TX_DP<13>")
		)
	)
)
